(kicad_pcb
	(version 20260206)
	(generator "pcbnew")
	(generator_version "10.0")
	(general
		(thickness 1.6)
		(legacy_teardrops no)
	)
	(paper "A4")
	(title_block
		(title "03242023_DA0F0TMBIJ0_F0T_Motherboard_J_brd_V01_OCP.brd")
		(comment 1 "Grand Teton / footprints 5004-5009 of 6105")
	)
	(layers
		(0 "F.Cu" signal "TOP")
		(4 "In1.Cu" signal "GND")
		(6 "In2.Cu" signal "IN1")
		(8 "In3.Cu" signal "GND1")
		(10 "In4.Cu" signal "IN2")
		(12 "In5.Cu" signal "GND2")
		(14 "In6.Cu" signal "IN3")
		(16 "In7.Cu" signal "GND3")
		(18 "In8.Cu" signal "VCC")
		(20 "In9.Cu" signal "VCC1")
		(22 "In10.Cu" signal "GND4")
		(24 "In11.Cu" signal "IN4")
		(26 "In12.Cu" signal "GND5")
		(28 "In13.Cu" signal "IN5")
		(30 "In14.Cu" signal "GND6")
		(32 "In15.Cu" signal "IN6")
		(34 "In16.Cu" signal "GND7")
		(2 "B.Cu" signal "BOTTOM")
		(9 "F.Adhes" user "F.Adhesive")
		(11 "B.Adhes" user "B.Adhesive")
		(13 "F.Paste" user "Package Geometry/Pastemask Top")
		(15 "B.Paste" user "Package Geometry/Pastemask Bottom")
		(5 "F.SilkS" user "Ref Des/Silkscreen Top")
		(7 "B.SilkS" user "Ref Des/Silkscreen Bottom")
		(1 "F.Mask" user "Board Geometry/Soldermask Top")
		(3 "B.Mask" user "Board Geometry/Soldermask Bottom")
		(17 "Dwgs.User" user "User.Drawings")
		(19 "Cmts.User" user "User.Comments")
		(21 "Eco1.User" user "User.Eco1")
		(23 "Eco2.User" user "User.Eco2")
		(25 "Edge.Cuts" user "Board Geometry/Outline")
		(27 "Margin" user)
		(31 "F.CrtYd" user "Package Geometry/Place Bound Top")
		(29 "B.CrtYd" user "Package Geometry/Place Bound Bottom")
		(35 "F.Fab" user "Ref Des/Assembly Top")
		(33 "B.Fab" user "Ref Des/Assembly Bottom")
	)
	(footprint ""
		(layer "B.Cu")
		(at 179.729638 -13.762228 90)
		(property "Reference" "R2422"
			(at 0 0 90)
			(layer "B.SilkS")
			(hide yes)
			(effects
				(font
					(size 1.27 1.27)
				)
				(justify mirror)
			)
		)
		(property "Value" ""
			(at 0 0 90)
			(layer "B.Fab")
			(effects
				(font
					(size 1.27 1.27)
				)
				(justify mirror)
			)
		)
		(duplicate_pad_numbers_are_jumpers no)
		(fp_line
			(start 0.7874 -0.4064)
			(end -0.7874 -0.4064)
			(stroke
				(width 0.1524)
				(type default)
			)
			(layer "B.SilkS")
		)
		(fp_line
			(start -0.7874 -0.4064)
			(end -0.7874 0.4064)
			(stroke
				(width 0.1524)
				(type default)
			)
			(layer "B.SilkS")
		)
		(fp_line
			(start 0.7874 0.4064)
			(end 0.7874 -0.4064)
			(stroke
				(width 0.1524)
				(type default)
			)
			(layer "B.SilkS")
		)
		(fp_line
			(start -0.7874 0.4064)
			(end 0.7874 0.4064)
			(stroke
				(width 0.1524)
				(type default)
			)
			(layer "B.SilkS")
		)
		(fp_line
			(start 0.67945 -0.305054)
			(end 0.12065 -0.305054)
			(stroke
				(width 0.1)
				(type default)
			)
			(layer "B.Fab")
		)
		(fp_line
			(start 0.12065 -0.305054)
			(end 0.12065 -0.2794)
			(stroke
				(width 0.1)
				(type default)
			)
			(layer "B.Fab")
		)
		(fp_line
			(start -0.12065 -0.3048)
			(end -0.67945 -0.3048)
			(stroke
				(width 0.1)
				(type default)
			)
			(layer "B.Fab")
		)
		(fp_line
			(start -0.67945 -0.3048)
			(end -0.67945 0.3048)
			(stroke
				(width 0.1)
				(type default)
			)
			(layer "B.Fab")
		)
		(fp_line
			(start 0.12065 -0.2794)
			(end -0.12065 -0.2794)
			(stroke
				(width 0.1)
				(type default)
			)
			(layer "B.Fab")
		)
		(fp_line
			(start -0.12065 -0.2794)
			(end -0.12065 -0.3048)
			(stroke
				(width 0.1)
				(type default)
			)
			(layer "B.Fab")
		)
		(fp_line
			(start 0.12065 0.2794)
			(end 0.12065 0.3048)
			(stroke
				(width 0.1)
				(type default)
			)
			(layer "B.Fab")
		)
		(fp_line
			(start -0.120396 0.2794)
			(end 0.12065 0.2794)
			(stroke
				(width 0.1)
				(type default)
			)
			(layer "B.Fab")
		)
		(fp_line
			(start 0.67945 0.3048)
			(end 0.67945 -0.305054)
			(stroke
				(width 0.1)
				(type default)
			)
			(layer "B.Fab")
		)
		(fp_line
			(start 0.12065 0.3048)
			(end 0.67945 0.3048)
			(stroke
				(width 0.1)
				(type default)
			)
			(layer "B.Fab")
		)
		(fp_line
			(start -0.120396 0.3048)
			(end -0.120396 0.2794)
			(stroke
				(width 0.1)
				(type default)
			)
			(layer "B.Fab")
		)
		(fp_line
			(start -0.67945 0.3048)
			(end -0.120396 0.3048)
			(stroke
				(width 0.1)
				(type default)
			)
			(layer "B.Fab")
		)
		(pad "1" smd circle
			(at 0.40005 0 270)
			(size 0 0)
			(layers "B.Cu" "B.Mask" "B.Paste")
			(net "SMB_VR_SENSOR_3V3AUX_SDA")
		)
		(pad "2" smd circle
			(at -0.40005 0 270)
			(size 0 0)
			(layers "B.Cu" "B.Mask" "B.Paste")
			(net "SMB_VR_3V3AUX_SDA_R0")
		)
	)
	(footprint ""
		(layer "B.Cu")
		(at 258.953 -98.008948)
		(property "Reference" "C171"
			(at 0 0 0)
			(layer "B.SilkS")
			(hide yes)
			(effects
				(font
					(size 1.27 1.27)
				)
				(justify mirror)
			)
		)
		(property "Value" ""
			(at 0 0 0)
			(layer "B.Fab")
			(effects
				(font
					(size 1.27 1.27)
				)
				(justify mirror)
			)
		)
		(duplicate_pad_numbers_are_jumpers no)
		(fp_line
			(start -0.7874 -0.4064)
			(end -0.7874 0.4064)
			(stroke
				(width 0.1524)
				(type default)
			)
			(layer "B.SilkS")
		)
		(fp_line
			(start -0.7874 0.4064)
			(end 0.7874 0.4064)
			(stroke
				(width 0.1524)
				(type default)
			)
			(layer "B.SilkS")
		)
		(fp_line
			(start 0.7874 -0.4064)
			(end -0.7874 -0.4064)
			(stroke
				(width 0.1524)
				(type default)
			)
			(layer "B.SilkS")
		)
		(fp_line
			(start 0.7874 0.4064)
			(end 0.7874 -0.4064)
			(stroke
				(width 0.1524)
				(type default)
			)
			(layer "B.SilkS")
		)
		(fp_line
			(start -0.67945 -0.3048)
			(end -0.67945 0.3048)
			(stroke
				(width 0.1)
				(type default)
			)
			(layer "B.Fab")
		)
		(fp_line
			(start -0.67945 0.3048)
			(end -0.120396 0.3048)
			(stroke
				(width 0.1)
				(type default)
			)
			(layer "B.Fab")
		)
		(fp_line
			(start -0.12065 -0.3048)
			(end -0.67945 -0.3048)
			(stroke
				(width 0.1)
				(type default)
			)
			(layer "B.Fab")
		)
		(fp_line
			(start -0.12065 -0.2794)
			(end -0.12065 -0.3048)
			(stroke
				(width 0.1)
				(type default)
			)
			(layer "B.Fab")
		)
		(fp_line
			(start -0.120396 0.2794)
			(end 0.12065 0.2794)
			(stroke
				(width 0.1)
				(type default)
			)
			(layer "B.Fab")
		)
		(fp_line
			(start -0.120396 0.3048)
			(end -0.120396 0.2794)
			(stroke
				(width 0.1)
				(type default)
			)
			(layer "B.Fab")
		)
		(fp_line
			(start 0.12065 -0.305054)
			(end 0.12065 -0.2794)
			(stroke
				(width 0.1)
				(type default)
			)
			(layer "B.Fab")
		)
		(fp_line
			(start 0.12065 -0.2794)
			(end -0.12065 -0.2794)
			(stroke
				(width 0.1)
				(type default)
			)
			(layer "B.Fab")
		)
		(fp_line
			(start 0.12065 0.2794)
			(end 0.12065 0.3048)
			(stroke
				(width 0.1)
				(type default)
			)
			(layer "B.Fab")
		)
		(fp_line
			(start 0.12065 0.3048)
			(end 0.67945 0.3048)
			(stroke
				(width 0.1)
				(type default)
			)
			(layer "B.Fab")
		)
		(fp_line
			(start 0.67945 -0.305054)
			(end 0.12065 -0.305054)
			(stroke
				(width 0.1)
				(type default)
			)
			(layer "B.Fab")
		)
		(fp_line
			(start 0.67945 0.3048)
			(end 0.67945 -0.305054)
			(stroke
				(width 0.1)
				(type default)
			)
			(layer "B.Fab")
		)
		(pad "1" smd circle
			(at 0.40005 0 180)
			(size 0 0)
			(layers "B.Cu" "B.Mask" "B.Paste")
			(net "P3V3_AUX_CLK_GEN_VDD_CK440")
		)
		(pad "2" smd circle
			(at -0.40005 0 180)
			(size 0 0)
			(layers "B.Cu" "B.Mask" "B.Paste")
			(net "GND")
		)
	)
	(footprint ""
		(layer "B.Cu")
		(at 203.33208 -36.642548 180)
		(property "Reference" "R3578"
			(at 0 0 0)
			(layer "B.SilkS")
			(hide yes)
			(effects
				(font
					(size 1.27 1.27)
				)
				(justify mirror)
			)
		)
		(property "Value" ""
			(at 0 0 0)
			(layer "B.Fab")
			(effects
				(font
					(size 1.27 1.27)
				)
				(justify mirror)
			)
		)
		(duplicate_pad_numbers_are_jumpers no)
		(fp_line
			(start 0.7874 0.4064)
			(end 0.7874 -0.4064)
			(stroke
				(width 0.1524)
				(type default)
			)
			(layer "B.SilkS")
		)
		(fp_line
			(start 0.7874 -0.4064)
			(end -0.7874 -0.4064)
			(stroke
				(width 0.1524)
				(type default)
			)
			(layer "B.SilkS")
		)
		(fp_line
			(start -0.7874 0.4064)
			(end 0.7874 0.4064)
			(stroke
				(width 0.1524)
				(type default)
			)
			(layer "B.SilkS")
		)
		(fp_line
			(start -0.7874 -0.4064)
			(end -0.7874 0.4064)
			(stroke
				(width 0.1524)
				(type default)
			)
			(layer "B.SilkS")
		)
		(fp_line
			(start 0.67945 0.3048)
			(end 0.67945 -0.305054)
			(stroke
				(width 0.1)
				(type default)
			)
			(layer "B.Fab")
		)
		(fp_line
			(start 0.67945 -0.305054)
			(end 0.12065 -0.305054)
			(stroke
				(width 0.1)
				(type default)
			)
			(layer "B.Fab")
		)
		(fp_line
			(start 0.12065 0.3048)
			(end 0.67945 0.3048)
			(stroke
				(width 0.1)
				(type default)
			)
			(layer "B.Fab")
		)
		(fp_line
			(start 0.12065 0.2794)
			(end 0.12065 0.3048)
			(stroke
				(width 0.1)
				(type default)
			)
			(layer "B.Fab")
		)
		(fp_line
			(start 0.12065 -0.2794)
			(end -0.12065 -0.2794)
			(stroke
				(width 0.1)
				(type default)
			)
			(layer "B.Fab")
		)
		(fp_line
			(start 0.12065 -0.305054)
			(end 0.12065 -0.2794)
			(stroke
				(width 0.1)
				(type default)
			)
			(layer "B.Fab")
		)
		(fp_line
			(start -0.120396 0.3048)
			(end -0.120396 0.2794)
			(stroke
				(width 0.1)
				(type default)
			)
			(layer "B.Fab")
		)
		(fp_line
			(start -0.120396 0.2794)
			(end 0.12065 0.2794)
			(stroke
				(width 0.1)
				(type default)
			)
			(layer "B.Fab")
		)
		(fp_line
			(start -0.12065 -0.2794)
			(end -0.12065 -0.3048)
			(stroke
				(width 0.1)
				(type default)
			)
			(layer "B.Fab")
		)
		(fp_line
			(start -0.12065 -0.3048)
			(end -0.67945 -0.3048)
			(stroke
				(width 0.1)
				(type default)
			)
			(layer "B.Fab")
		)
		(fp_line
			(start -0.67945 0.3048)
			(end -0.120396 0.3048)
			(stroke
				(width 0.1)
				(type default)
			)
			(layer "B.Fab")
		)
		(fp_line
			(start -0.67945 -0.3048)
			(end -0.67945 0.3048)
			(stroke
				(width 0.1)
				(type default)
			)
			(layer "B.Fab")
		)
		(pad "1" smd circle
			(at 0.40005 0)
			(size 0 0)
			(layers "B.Cu" "B.Mask" "B.Paste")
			(net "P12V_SCM_R")
		)
		(pad "2" smd circle
			(at -0.40005 0)
			(size 0 0)
			(layers "B.Cu" "B.Mask" "B.Paste")
			(net "VSENSE_P12V_INA230_5_INP")
		)
	)
	(footprint ""
		(layer "B.Cu")
		(at 109.45114 -356.507288 -90)
		(property "Reference" "PR4239"
			(at 0 0 90)
			(layer "B.SilkS")
			(hide yes)
			(effects
				(font
					(size 1.27 1.27)
				)
				(justify mirror)
			)
		)
		(property "Value" ""
			(at 0 0 90)
			(layer "B.Fab")
			(effects
				(font
					(size 1.27 1.27)
				)
				(justify mirror)
			)
		)
		(duplicate_pad_numbers_are_jumpers no)
		(fp_line
			(start -0.7874 0.4064)
			(end 0.7874 0.4064)
			(stroke
				(width 0.1524)
				(type default)
			)
			(layer "B.SilkS")
		)
		(fp_line
			(start 0.7874 0.4064)
			(end 0.7874 -0.4064)
			(stroke
				(width 0.1524)
				(type default)
			)
			(layer "B.SilkS")
		)
		(fp_line
			(start -0.7874 -0.4064)
			(end -0.7874 0.4064)
			(stroke
				(width 0.1524)
				(type default)
			)
			(layer "B.SilkS")
		)
		(fp_line
			(start 0.7874 -0.4064)
			(end -0.7874 -0.4064)
			(stroke
				(width 0.1524)
				(type default)
			)
			(layer "B.SilkS")
		)
		(fp_line
			(start -0.67945 0.3048)
			(end -0.120396 0.3048)
			(stroke
				(width 0.1)
				(type default)
			)
			(layer "B.Fab")
		)
		(fp_line
			(start -0.120396 0.3048)
			(end -0.120396 0.2794)
			(stroke
				(width 0.1)
				(type default)
			)
			(layer "B.Fab")
		)
		(fp_line
			(start 0.12065 0.3048)
			(end 0.67945 0.3048)
			(stroke
				(width 0.1)
				(type default)
			)
			(layer "B.Fab")
		)
		(fp_line
			(start 0.67945 0.3048)
			(end 0.67945 -0.305054)
			(stroke
				(width 0.1)
				(type default)
			)
			(layer "B.Fab")
		)
		(fp_line
			(start -0.120396 0.2794)
			(end 0.12065 0.2794)
			(stroke
				(width 0.1)
				(type default)
			)
			(layer "B.Fab")
		)
		(fp_line
			(start 0.12065 0.2794)
			(end 0.12065 0.3048)
			(stroke
				(width 0.1)
				(type default)
			)
			(layer "B.Fab")
		)
		(fp_line
			(start -0.12065 -0.2794)
			(end -0.12065 -0.3048)
			(stroke
				(width 0.1)
				(type default)
			)
			(layer "B.Fab")
		)
		(fp_line
			(start 0.12065 -0.2794)
			(end -0.12065 -0.2794)
			(stroke
				(width 0.1)
				(type default)
			)
			(layer "B.Fab")
		)
		(fp_line
			(start -0.67945 -0.3048)
			(end -0.67945 0.3048)
			(stroke
				(width 0.1)
				(type default)
			)
			(layer "B.Fab")
		)
		(fp_line
			(start -0.12065 -0.3048)
			(end -0.67945 -0.3048)
			(stroke
				(width 0.1)
				(type default)
			)
			(layer "B.Fab")
		)
		(fp_line
			(start 0.12065 -0.305054)
			(end 0.12065 -0.2794)
			(stroke
				(width 0.1)
				(type default)
			)
			(layer "B.Fab")
		)
		(fp_line
			(start 0.67945 -0.305054)
			(end 0.12065 -0.305054)
			(stroke
				(width 0.1)
				(type default)
			)
			(layer "B.Fab")
		)
		(pad "1" smd circle
			(at 0.40005 0 90)
			(size 0 0)
			(layers "B.Cu" "B.Mask" "B.Paste")
			(net "PVCCFA_EHV_FIVRA_CPU1_IMON3")
		)
		(pad "2" smd circle
			(at -0.40005 0 90)
			(size 0 0)
			(layers "B.Cu" "B.Mask" "B.Paste")
			(net "GND")
		)
	)
	(footprint ""
		(layer "B.Cu")
		(at 252.222 -97.373948 180)
		(property "Reference" "C111"
			(at 0 0 0)
			(layer "B.SilkS")
			(hide yes)
			(effects
				(font
					(size 1.27 1.27)
				)
				(justify mirror)
			)
		)
		(property "Value" ""
			(at 0 0 0)
			(layer "B.Fab")
			(effects
				(font
					(size 1.27 1.27)
				)
				(justify mirror)
			)
		)
		(duplicate_pad_numbers_are_jumpers no)
		(fp_line
			(start 0.7874 0.4064)
			(end 0.7874 -0.4064)
			(stroke
				(width 0.1524)
				(type default)
			)
			(layer "B.SilkS")
		)
		(fp_line
			(start 0.7874 -0.4064)
			(end -0.7874 -0.4064)
			(stroke
				(width 0.1524)
				(type default)
			)
			(layer "B.SilkS")
		)
		(fp_line
			(start -0.7874 0.4064)
			(end 0.7874 0.4064)
			(stroke
				(width 0.1524)
				(type default)
			)
			(layer "B.SilkS")
		)
		(fp_line
			(start -0.7874 -0.4064)
			(end -0.7874 0.4064)
			(stroke
				(width 0.1524)
				(type default)
			)
			(layer "B.SilkS")
		)
		(fp_line
			(start 0.67945 0.3048)
			(end 0.67945 -0.305054)
			(stroke
				(width 0.1)
				(type default)
			)
			(layer "B.Fab")
		)
		(fp_line
			(start 0.67945 -0.305054)
			(end 0.12065 -0.305054)
			(stroke
				(width 0.1)
				(type default)
			)
			(layer "B.Fab")
		)
		(fp_line
			(start 0.12065 0.3048)
			(end 0.67945 0.3048)
			(stroke
				(width 0.1)
				(type default)
			)
			(layer "B.Fab")
		)
		(fp_line
			(start 0.12065 0.2794)
			(end 0.12065 0.3048)
			(stroke
				(width 0.1)
				(type default)
			)
			(layer "B.Fab")
		)
		(fp_line
			(start 0.12065 -0.2794)
			(end -0.12065 -0.2794)
			(stroke
				(width 0.1)
				(type default)
			)
			(layer "B.Fab")
		)
		(fp_line
			(start 0.12065 -0.305054)
			(end 0.12065 -0.2794)
			(stroke
				(width 0.1)
				(type default)
			)
			(layer "B.Fab")
		)
		(fp_line
			(start -0.120396 0.3048)
			(end -0.120396 0.2794)
			(stroke
				(width 0.1)
				(type default)
			)
			(layer "B.Fab")
		)
		(fp_line
			(start -0.120396 0.2794)
			(end 0.12065 0.2794)
			(stroke
				(width 0.1)
				(type default)
			)
			(layer "B.Fab")
		)
		(fp_line
			(start -0.12065 -0.2794)
			(end -0.12065 -0.3048)
			(stroke
				(width 0.1)
				(type default)
			)
			(layer "B.Fab")
		)
		(fp_line
			(start -0.12065 -0.3048)
			(end -0.67945 -0.3048)
			(stroke
				(width 0.1)
				(type default)
			)
			(layer "B.Fab")
		)
		(fp_line
			(start -0.67945 0.3048)
			(end -0.120396 0.3048)
			(stroke
				(width 0.1)
				(type default)
			)
			(layer "B.Fab")
		)
		(fp_line
			(start -0.67945 -0.3048)
			(end -0.67945 0.3048)
			(stroke
				(width 0.1)
				(type default)
			)
			(layer "B.Fab")
		)
		(pad "1" smd circle
			(at 0.40005 0)
			(size 0 0)
			(layers "B.Cu" "B.Mask" "B.Paste")
			(net "P3V3_AUX_CLK_GEN_VDDXTAL_CK440")
		)
		(pad "2" smd circle
			(at -0.40005 0)
			(size 0 0)
			(layers "B.Cu" "B.Mask" "B.Paste")
			(net "GND")
		)
	)
	(footprint ""
		(layer "B.Cu")
		(at 370.901468 -324.911466 -90)
		(property "Reference" "PC288_P0_4"
			(at 0 0 90)
			(layer "B.SilkS")
			(hide yes)
			(effects
				(font
					(size 1.27 1.27)
				)
				(justify mirror)
			)
		)
		(property "Value" ""
			(at 0 0 90)
			(layer "B.Fab")
			(effects
				(font
					(size 1.27 1.27)
				)
				(justify mirror)
			)
		)
		(duplicate_pad_numbers_are_jumpers no)
		(fp_line
			(start -1.524 0.762)
			(end 1.524 0.762)
			(stroke
				(width 0.1524)
				(type default)
			)
			(layer "B.SilkS")
		)
		(fp_line
			(start 1.524 0.762)
			(end 1.524 -0.762)
			(stroke
				(width 0.1524)
				(type default)
			)
			(layer "B.SilkS")
		)
		(fp_line
			(start -1.524 -0.762)
			(end -1.524 0.762)
			(stroke
				(width 0.1524)
				(type default)
			)
			(layer "B.SilkS")
		)
		(fp_line
			(start 1.524 -0.762)
			(end -1.524 -0.762)
			(stroke
				(width 0.1524)
				(type default)
			)
			(layer "B.SilkS")
		)
		(fp_line
			(start -1.1049 0.724916)
			(end -1.1049 -0.724916)
			(stroke
				(width 0.1)
				(type default)
			)
			(layer "B.Fab")
		)
		(fp_line
			(start 1.1049 0.724916)
			(end -1.1049 0.724916)
			(stroke
				(width 0.1)
				(type default)
			)
			(layer "B.Fab")
		)
		(fp_line
			(start -1.1049 -0.724916)
			(end 1.1049 -0.724916)
			(stroke
				(width 0.1)
				(type default)
			)
			(layer "B.Fab")
		)
		(fp_line
			(start 1.1049 -0.724916)
			(end 1.1049 0.724916)
			(stroke
				(width 0.1)
				(type default)
			)
			(layer "B.Fab")
		)
		(pad "1" smd rect
			(at 0.889 0 270)
			(size 1.016 1.27)
			(layers "B.Cu" "B.Mask" "B.Paste")
			(net "PVCCIN_CPU0")
		)
		(pad "2" smd rect
			(at -0.889 0 270)
			(size 1.016 1.27)
			(layers "B.Cu" "B.Mask" "B.Paste")
			(net "GND")
		)
	)
)
